#ISCELL
  mstr_misc dns *
  *
#ISCELL
  mstr_symbols cad_note *
  *
#ISCELL
  mstr_symbols design_note *
  *
#ISCELL
  mstr_symbols intel_corp_bpage *
  *
#CELL
  mstr_vreg tps2061 *
  page176_i100
#ISCELL
  mstr_symbols p5v *
  page176_i101
#ISCELL
  mstr_symbols gnd *
  page176_i102
#ISCELL
  mstr_standard offpage *
  page176_i103
#ISCELL
  mstr_standard offpage *
  page176_i104
#CELL
  mstr_discrete res *
  page176_i105
#ISCELL
  mstr_standard offpage *
  page176_i107
#CELL
  dev_discrete cap_a *
  page176_i108
#ISCELL
  mstr_symbols gnd *
  page176_i109
#ISCELL
  mstr_symbols p3v3_stby *
  page176_i110
#CELL
  mstr_discrete res *
  page176_i111
#ISCELL
  mstr_symbols gnd *
  page176_i112
#CELL
  mstr_discrete capp *
  page176_i113
#ISCELL
  mstr_symbols gnd *
  page176_i114
#ISCELL
  mstr_standard offpage *
  page176_i119
#ISCELL
  mstr_standard offpage *
  page176_i120
#ISCELL
  mstr_standard offpage *
  page176_i121
#CELL
  mstr_ttl ttl1g08 *
  page176_i122
#ISCELL
  mstr_standard offpage *
  page176_i123
#CELL
  mstr_discrete cap *
  page176_i124
#ISCELL
  mstr_symbols gnd *
  page176_i125
#ISCELL
  mstr_symbols p3v3_stby *
  page176_i126
#ISCELL
  mstr_standard offpage *
  page176_i127
#ISCELL
  mstr_standard offpage *
  page176_i128
#ISCELL
  mstr_standard offpage *
  page176_i129
#CELL
  mstr_discrete res *
  page176_i16
#CELL
  mstr_discrete choke_4pin *
  page176_i30
#CELL
  mstr_discrete res *
  page176_i31
#ISCELL
  mstr_standard offpage *
  page176_i46
#ISCELL
  mstr_standard offpage *
  page176_i47
#CELL
  mstr_conn conn9_h51826001 *
  page176_i69
#ISCELL
  mstr_symbols gnd *
  page176_i70
#ISCELL
  mstr_symbols gnd *
  page176_i71
#ISCELL
  mstr_standard offpage *
  page176_i75
#CELL
  mstr_discrete diodeac_dual_array *
  page176_i98
#ISCELL
  mstr_symbols gnd *
  page176_i99
